(kicad_pcb
	(version 20260206)
	(generator "pcbnew")
	(generator_version "10.0")
	(general
		(thickness 1.6)
		(legacy_teardrops no)
	)
	(paper "A4")
	(title_block
		(title "dpb — 14545-sa.0730WZS0815.brd")
		(comment 1 "Honey Badger (Wiwynn) / footprints 548-555 of 1066")
	)
	(layers
		(0 "F.Cu" signal "TOP")
		(4 "In1.Cu" signal "L2GND")
		(6 "In2.Cu" signal "L3")
		(8 "In3.Cu" signal "L4VCC")
		(10 "In4.Cu" signal "L5VCC")
		(12 "In5.Cu" signal "L6")
		(14 "In6.Cu" signal "L7GND")
		(2 "B.Cu" signal "BOTTOM")
		(9 "F.Adhes" user "F.Adhesive")
		(11 "B.Adhes" user "B.Adhesive")
		(13 "F.Paste" user "Package Geometry/Pastemask Top")
		(15 "B.Paste" user "Package Geometry/Pastemask Bottom")
		(5 "F.SilkS" user "Ref Des/Silkscreen Top")
		(7 "B.SilkS" user "Ref Des/Silkscreen Bottom")
		(1 "F.Mask" user "Board Geometry/Soldermask Top")
		(3 "B.Mask" user "Board Geometry/Soldermask Bottom")
		(17 "Dwgs.User" user "User.Drawings")
		(19 "Cmts.User" user "User.Comments")
		(21 "Eco1.User" user "User.Eco1")
		(23 "Eco2.User" user "User.Eco2")
		(25 "Edge.Cuts" user "Board Geometry/Outline")
		(27 "Margin" user)
		(31 "F.CrtYd" user "Package Geometry/Place Bound Top")
		(29 "B.CrtYd" user "Package Geometry/Place Bound Bottom")
		(35 "F.Fab" user "Ref Des/Assembly Top")
		(33 "B.Fab" user "Ref Des/Assembly Bottom")
	)
	(footprint ""
		(layer "F.Cu")
		(at 32.99968 -4.499864)
		(property "Reference" "H5"
			(at 0 0 0)
			(layer "F.SilkS")
			(hide yes)
			(effects
				(font
					(size 1.27 1.27)
				)
			)
		)
		(property "Value" "HOLE315R157"
			(at -0.116332 -8.41375 0)
			(unlocked yes)
			(layer "F.Fab")
			(hide yes)
			(effects
				(font
					(size 1.016 1.016)
					(thickness 0.1524)
				)
			)
		)
		(property "Device Type" "HOLE315R157"
			(at -0.116332 -6.88975 0)
			(unlocked yes)
			(layer "F.Fab")
			(hide yes)
			(effects
				(font
					(size 1.016 1.016)
					(thickness 0.1524)
				)
			)
		)
		(duplicate_pad_numbers_are_jumpers no)
		(fp_poly
			(pts
				(arc
					(start 4.3053 0)
					(mid -4.3053 0)
					(end 4.3053 0)
				)
			)
			(stroke
				(width 0)
				(type default)
			)
			(fill no)
			(layer "F.CrtYd")
		)
		(fp_poly
			(pts
				(arc
					(start 4.3053 0)
					(mid -4.3053 0)
					(end 4.3053 0)
				)
			)
			(stroke
				(width 0)
				(type default)
			)
			(fill no)
			(layer "F.Fab")
		)
		(pad "1" thru_hole circle
			(at 0 0)
			(size 8.001 8.001)
			(drill 3.9878)
			(layers "*.Cu" "*.Mask")
			(remove_unused_layers no)
			(net "GND")
			(clearance -1.4986)
			(thermal_gap 0.3048)
			(padstack
				(mode front_inner_back)
				(layer "Inner"
					(shape circle)
					(size 4.3942 4.3942)
					(clearance 0.3048)
				)
				(layer "B.Cu"
					(shape circle)
					(size 8.001 8.001)
					(clearance -1.4986)
				)
			)
		)
	)
	(footprint ""
		(layer "F.Cu")
		(at 8.127746 -487.8197 180)
		(property "Reference" "PR36"
			(at 0 0 180)
			(layer "F.SilkS")
			(hide yes)
			(effects
				(font
					(size 1.27 1.27)
				)
			)
		)
		(property "Value" "3D01R2F-GP"
			(at 0.064008 -3.993896 180)
			(unlocked yes)
			(layer "F.Fab")
			(hide yes)
			(effects
				(font
					(size 1.016 1.016)
					(thickness 0.1524)
				)
			)
		)
		(property "Device Type" "R402H16"
			(at 0.064008 -5.517896 180)
			(unlocked yes)
			(layer "F.Fab")
			(hide yes)
			(effects
				(font
					(size 1.016 1.016)
					(thickness 0.1524)
				)
			)
		)
		(duplicate_pad_numbers_are_jumpers no)
		(fp_line
			(start 0.508 -0.9398)
			(end -0.508 -0.9398)
			(stroke
				(width 0.1524)
				(type default)
			)
			(layer "F.SilkS")
		)
		(fp_line
			(start -0.508 -0.9398)
			(end -0.508 0.9398)
			(stroke
				(width 0.1524)
				(type default)
			)
			(layer "F.SilkS")
		)
		(fp_rect
			(start -0.508 0.9398)
			(end 0.508 -0.9398)
			(stroke
				(width 0)
				(type default)
			)
			(fill no)
			(layer "F.CrtYd")
		)
		(fp_rect
			(start -0.508 0.9398)
			(end 0.508 -0.9398)
			(stroke
				(width 0)
				(type default)
			)
			(fill no)
			(layer "F.Fab")
		)
		(pad "1" smd custom
			(at 0 -0.4445 180)
			(size 0.1397 0.1397)
			(layers "F.Cu" "F.Mask" "F.Paste")
			(net "GND")
			(options
				(clearance outline)
				(anchor circle)
			)
			(primitives
				(gr_poly
					(pts
						(arc
							(start -0.1778 -0.2794)
							(mid -0.249642 -0.249642)
							(end -0.2794 -0.1778)
						)
						(arc
							(start -0.2794 0.1778)
							(mid -0.249642 0.249642)
							(end -0.1778 0.2794)
						)
						(arc
							(start 0.1778 0.2794)
							(mid 0.249642 0.249642)
							(end 0.2794 0.1778)
						)
						(arc
							(start 0.2794 -0.1778)
							(mid 0.249642 -0.249642)
							(end 0.1778 -0.2794)
						)
					)
					(width 0)
					(fill yes)
				)
			)
		)
		(pad "2" smd custom
			(at 0 0.4445 180)
			(size 0.1397 0.1397)
			(layers "F.Cu" "F.Mask" "F.Paste")
			(net "P5VC_SNB")
			(options
				(clearance outline)
				(anchor circle)
			)
			(primitives
				(gr_poly
					(pts
						(arc
							(start -0.1778 -0.2794)
							(mid -0.249642 -0.249642)
							(end -0.2794 -0.1778)
						)
						(arc
							(start -0.2794 0.1778)
							(mid -0.249642 0.249642)
							(end -0.1778 0.2794)
						)
						(arc
							(start 0.1778 0.2794)
							(mid 0.249642 0.249642)
							(end 0.2794 0.1778)
						)
						(arc
							(start 0.2794 -0.1778)
							(mid 0.249642 -0.249642)
							(end 0.1778 -0.2794)
						)
					)
					(width 0)
					(fill yes)
				)
			)
		)
	)
	(footprint ""
		(layer "F.Cu")
		(at 55.245 -276.098)
		(property "Reference" "R208"
			(at 0 0 0)
			(layer "F.SilkS")
			(hide yes)
			(effects
				(font
					(size 1.27 1.27)
				)
			)
		)
		(property "Value" "220R3F-1-GP"
			(at -0.0254 -2.5146 0)
			(unlocked yes)
			(layer "F.Fab")
			(hide yes)
			(effects
				(font
					(size 1.016 1.016)
					(thickness 0.1524)
				)
			)
		)
		(property "Device Type" "R603H22"
			(at -0.0254 -4.0386 0)
			(unlocked yes)
			(layer "F.Fab")
			(hide yes)
			(effects
				(font
					(size 1.016 1.016)
					(thickness 0.1524)
				)
			)
		)
		(duplicate_pad_numbers_are_jumpers no)
		(fp_line
			(start -0.4826 0)
			(end -0.2032 0)
			(stroke
				(width 0.2032)
				(type default)
			)
			(layer "F.SilkS")
		)
		(fp_line
			(start 0.2032 0)
			(end 0.4826 0)
			(stroke
				(width 0.2032)
				(type default)
			)
			(layer "F.SilkS")
		)
		(fp_rect
			(start -0.5842 1.3335)
			(end 0.5842 -1.3335)
			(stroke
				(width 0)
				(type default)
			)
			(fill no)
			(layer "F.CrtYd")
		)
		(fp_rect
			(start -0.5842 1.3335)
			(end 0.5842 -1.3335)
			(stroke
				(width 0)
				(type default)
			)
			(fill no)
			(layer "F.Fab")
		)
		(pad "1" smd custom
			(at 0 -0.762)
			(size 0.2159 0.2159)
			(layers "F.Cu" "F.Mask" "F.Paste")
			(net "HDD_PRSNT_NET7")
			(options
				(clearance outline)
				(anchor circle)
			)
			(primitives
				(gr_poly
					(pts
						(arc
							(start -0.3302 -0.4318)
							(mid -0.402042 -0.402042)
							(end -0.4318 -0.3302)
						)
						(arc
							(start -0.4318 0.3302)
							(mid -0.402042 0.402042)
							(end -0.3302 0.4318)
						)
						(arc
							(start 0.3302 0.4318)
							(mid 0.402042 0.402042)
							(end 0.4318 0.3302)
						)
						(arc
							(start 0.4318 -0.3302)
							(mid 0.402042 -0.402042)
							(end 0.3302 -0.4318)
						)
					)
					(width 0)
					(fill yes)
				)
			)
		)
		(pad "2" smd custom
			(at 0 0.762)
			(size 0.2159 0.2159)
			(layers "F.Cu" "F.Mask" "F.Paste")
			(net "HDD_PRSNT7")
			(options
				(clearance outline)
				(anchor circle)
			)
			(primitives
				(gr_poly
					(pts
						(arc
							(start -0.3302 -0.4318)
							(mid -0.402042 -0.402042)
							(end -0.4318 -0.3302)
						)
						(arc
							(start -0.4318 0.3302)
							(mid -0.402042 0.402042)
							(end -0.3302 0.4318)
						)
						(arc
							(start 0.3302 0.4318)
							(mid 0.402042 0.402042)
							(end 0.4318 0.3302)
						)
						(arc
							(start 0.4318 -0.3302)
							(mid 0.402042 -0.402042)
							(end 0.3302 -0.4318)
						)
					)
					(width 0)
					(fill yes)
				)
			)
		)
	)
	(footprint ""
		(layer "F.Cu")
		(at 193.758058 -392.886184 -90)
		(property "Reference" "Q4"
			(at 0 0 270)
			(layer "F.SilkS")
			(hide yes)
			(effects
				(font
					(size 1.27 1.27)
				)
			)
		)
		(property "Value" "2N7002DW-7F-GP"
			(at -2.3622 -8.2042 270)
			(unlocked yes)
			(layer "F.Fab")
			(hide yes)
			(effects
				(font
					(size 1.016 1.016)
					(thickness 0.1524)
				)
			)
		)
		(property "Device Type" "SOT-363H44"
			(at -2.3622 -10.1092 270)
			(unlocked yes)
			(layer "F.Fab")
			(hide yes)
			(effects
				(font
					(size 1.016 1.016)
					(thickness 0.1524)
				)
			)
		)
		(duplicate_pad_numbers_are_jumpers no)
		(fp_line
			(start -1.4478 1.7018)
			(end 1.4478 1.7018)
			(stroke
				(width 0.1524)
				(type default)
			)
			(layer "F.SilkS")
		)
		(fp_line
			(start 1.4478 1.7018)
			(end 1.4478 -1.7018)
			(stroke
				(width 0.1524)
				(type default)
			)
			(layer "F.SilkS")
		)
		(fp_line
			(start -1.27 1.524)
			(end -1.27 0.6604)
			(stroke
				(width 0.4826)
				(type default)
			)
			(layer "F.SilkS")
		)
		(fp_line
			(start -1.4478 -1.7018)
			(end -1.4478 1.7018)
			(stroke
				(width 0.1524)
				(type default)
			)
			(layer "F.SilkS")
		)
		(fp_line
			(start 1.4478 -1.7018)
			(end -1.4478 -1.7018)
			(stroke
				(width 0.1524)
				(type default)
			)
			(layer "F.SilkS")
		)
		(fp_poly
			(pts
				(xy -1.524 -1.778) (xy 1.524 -1.778) (xy 1.524 1.778) (xy -1.524 1.778)
			)
			(stroke
				(width 0)
				(type default)
			)
			(fill no)
			(layer "F.CrtYd")
		)
		(fp_poly
			(pts
				(xy -1.524 -1.778) (xy 1.524 -1.778) (xy 1.524 1.778) (xy -1.524 1.778)
			)
			(stroke
				(width 0)
				(type default)
			)
			(fill no)
			(layer "F.Fab")
		)
		(pad "1" smd rect
			(at -0.65024 0.9398 270)
			(size 0.4064 1.016)
			(layers "F.Cu" "F.Mask" "F.Paste")
			(net "GND")
		)
		(pad "2" smd rect
			(at 0 0.9398 270)
			(size 0.4064 1.016)
			(layers "F.Cu" "F.Mask" "F.Paste")
			(net "SW_PWR_R_HDD1")
		)
		(pad "3" smd rect
			(at 0.65024 0.9398 270)
			(size 0.4064 1.016)
			(layers "F.Cu" "F.Mask" "F.Paste")
			(net "SW_HDD1_P")
		)
		(pad "4" smd rect
			(at 0.65024 -0.9398 270)
			(size 0.4064 1.016)
			(layers "F.Cu" "F.Mask" "F.Paste")
			(net "GND")
		)
		(pad "5" smd rect
			(at 0 -0.9398 270)
			(size 0.4064 1.016)
			(layers "F.Cu" "F.Mask" "F.Paste")
			(net "SW_HDD1_G")
		)
		(pad "6" smd rect
			(at -0.65024 -0.9398 270)
			(size 0.4064 1.016)
			(layers "F.Cu" "F.Mask" "F.Paste")
			(net "SW_HDD1_R")
		)
	)
	(footprint ""
		(layer "F.Cu")
		(at 216.364058 -389.711184 -90)
		(property "Reference" "R124"
			(at 0 0 270)
			(layer "F.SilkS")
			(hide yes)
			(effects
				(font
					(size 1.27 1.27)
				)
			)
		)
		(property "Value" "2R2010J-1-GP"
			(at 0.254 -8.0772 270)
			(unlocked yes)
			(layer "F.Fab")
			(hide yes)
			(effects
				(font
					(size 1.016 1.016)
					(thickness 0.1524)
				)
			)
		)
		(property "Device Type" "R2010H28"
			(at 0.254 -9.6774 270)
			(unlocked yes)
			(layer "F.Fab")
			(hide yes)
			(effects
				(font
					(size 1.016 1.016)
					(thickness 0.1524)
				)
			)
		)
		(duplicate_pad_numbers_are_jumpers no)
		(fp_line
			(start -1.651 3.302)
			(end 1.651 3.302)
			(stroke
				(width 0.1524)
				(type default)
			)
			(layer "F.SilkS")
		)
		(fp_line
			(start 1.651 3.302)
			(end 1.651 -3.302)
			(stroke
				(width 0.1524)
				(type default)
			)
			(layer "F.SilkS")
		)
		(fp_line
			(start -1.651 -3.302)
			(end -1.651 3.302)
			(stroke
				(width 0.1524)
				(type default)
			)
			(layer "F.SilkS")
		)
		(fp_line
			(start 1.651 -3.302)
			(end -1.651 -3.302)
			(stroke
				(width 0.1524)
				(type default)
			)
			(layer "F.SilkS")
		)
		(fp_rect
			(start -1.7272 -3.3782)
			(end 1.7272 3.3782)
			(stroke
				(width 0)
				(type default)
			)
			(fill no)
			(layer "F.CrtYd")
		)
		(fp_poly
			(pts
				(xy 1.7272 3.3782) (xy 1.7272 -3.3782) (xy -1.7272 -3.3782) (xy -1.7272 3.3782)
			)
			(stroke
				(width 0)
				(type default)
			)
			(fill no)
			(layer "F.Fab")
		)
		(pad "1" smd rect
			(at 0 -2.3495 270)
			(size 2.794 1.143)
			(layers "F.Cu" "F.Mask" "F.Paste")
			(net "12V_PRE_1")
		)
		(pad "2" smd rect
			(at 0 2.3495 270)
			(size 2.794 1.143)
			(layers "F.Cu" "F.Mask" "F.Paste")
			(net "P12V_HDD1")
		)
	)
	(footprint ""
		(layer "F.Cu")
		(at 26.669746 -432.781202 180)
		(property "Reference" "C270"
			(at 0 0 180)
			(layer "F.SilkS")
			(hide yes)
			(effects
				(font
					(size 1.27 1.27)
				)
			)
		)
		(property "Value" "SCD01U50V2KX-1GP"
			(at 1.1811 -2.7051 180)
			(unlocked yes)
			(layer "F.Fab")
			(hide yes)
			(effects
				(font
					(size 1.016 1.016)
					(thickness 0.1524)
				)
			)
		)
		(property "Device Type" "C402H22"
			(at 1.1811 -4.2291 180)
			(unlocked yes)
			(layer "F.Fab")
			(hide yes)
			(effects
				(font
					(size 1.016 1.016)
					(thickness 0.1524)
				)
			)
		)
		(duplicate_pad_numbers_are_jumpers no)
		(fp_rect
			(start -0.4318 0.9525)
			(end 0.4318 -0.9525)
			(stroke
				(width 0)
				(type default)
			)
			(fill no)
			(layer "F.CrtYd")
		)
		(fp_rect
			(start -0.4318 0.9525)
			(end 0.4318 -0.9525)
			(stroke
				(width 0)
				(type default)
			)
			(fill no)
			(layer "F.Fab")
		)
		(pad "1" smd custom
			(at 0 -0.4445 180)
			(size 0.1524 0.1524)
			(layers "F.Cu" "F.Mask" "F.Paste")
			(net "HDD_PRSNT_NET10")
			(options
				(clearance outline)
				(anchor circle)
			)
			(primitives
				(gr_poly
					(pts
						(arc
							(start 0.3048 -0.2032)
							(mid 0.275042 -0.275042)
							(end 0.2032 -0.3048)
						)
						(arc
							(start -0.2032 -0.3048)
							(mid -0.275042 -0.275042)
							(end -0.3048 -0.2032)
						)
						(arc
							(start -0.3048 0.2032)
							(mid -0.275042 0.275042)
							(end -0.2032 0.3048)
						)
						(arc
							(start 0.2032 0.3048)
							(mid 0.275042 0.275042)
							(end 0.3048 0.2032)
						)
					)
					(width 0)
					(fill yes)
				)
			)
		)
		(pad "2" smd custom
			(at 0 0.4445 180)
			(size 0.1524 0.1524)
			(layers "F.Cu" "F.Mask" "F.Paste")
			(net "GND")
			(options
				(clearance outline)
				(anchor circle)
			)
			(primitives
				(gr_poly
					(pts
						(arc
							(start 0.3048 -0.2032)
							(mid 0.275042 -0.275042)
							(end 0.2032 -0.3048)
						)
						(arc
							(start -0.2032 -0.3048)
							(mid -0.275042 -0.275042)
							(end -0.3048 -0.2032)
						)
						(arc
							(start -0.3048 0.2032)
							(mid -0.275042 0.275042)
							(end -0.2032 0.3048)
						)
						(arc
							(start 0.2032 0.3048)
							(mid 0.275042 0.275042)
							(end 0.3048 0.2032)
						)
					)
					(width 0)
					(fill yes)
				)
			)
		)
	)
	(footprint ""
		(layer "F.Cu")
		(at 45.338746 -41.9227 90)
		(property "Reference" "R226"
			(at 0 0 90)
			(layer "F.SilkS")
			(hide yes)
			(effects
				(font
					(size 1.27 1.27)
				)
			)
		)
		(property "Value" "10KR2F-2-GP"
			(at 0.064008 -3.993896 90)
			(unlocked yes)
			(layer "F.Fab")
			(hide yes)
			(effects
				(font
					(size 1.016 1.016)
					(thickness 0.1524)
				)
			)
		)
		(property "Device Type" "R402H16"
			(at 0.064008 -5.517896 90)
			(unlocked yes)
			(layer "F.Fab")
			(hide yes)
			(effects
				(font
					(size 1.016 1.016)
					(thickness 0.1524)
				)
			)
		)
		(duplicate_pad_numbers_are_jumpers no)
		(fp_line
			(start 0.508 -0.9398)
			(end -0.508 -0.9398)
			(stroke
				(width 0.1524)
				(type default)
			)
			(layer "F.SilkS")
		)
		(fp_line
			(start -0.508 -0.9398)
			(end -0.508 0.9398)
			(stroke
				(width 0.1524)
				(type default)
			)
			(layer "F.SilkS")
		)
		(fp_rect
			(start -0.508 0.9398)
			(end 0.508 -0.9398)
			(stroke
				(width 0)
				(type default)
			)
			(fill no)
			(layer "F.CrtYd")
		)
		(fp_rect
			(start -0.508 0.9398)
			(end 0.508 -0.9398)
			(stroke
				(width 0)
				(type default)
			)
			(fill no)
			(layer "F.Fab")
		)
		(pad "1" smd custom
			(at 0 -0.4445 90)
			(size 0.1397 0.1397)
			(layers "F.Cu" "F.Mask" "F.Paste")
			(net "P5VB")
			(options
				(clearance outline)
				(anchor circle)
			)
			(primitives
				(gr_poly
					(pts
						(arc
							(start -0.1778 -0.2794)
							(mid -0.249642 -0.249642)
							(end -0.2794 -0.1778)
						)
						(arc
							(start -0.2794 0.1778)
							(mid -0.249642 0.249642)
							(end -0.1778 0.2794)
						)
						(arc
							(start 0.1778 0.2794)
							(mid 0.249642 0.249642)
							(end 0.2794 0.1778)
						)
						(arc
							(start 0.2794 -0.1778)
							(mid 0.249642 -0.249642)
							(end 0.1778 -0.2794)
						)
					)
					(width 0)
					(fill yes)
				)
			)
		)
		(pad "2" smd custom
			(at 0 0.4445 90)
			(size 0.1397 0.1397)
			(layers "F.Cu" "F.Mask" "F.Paste")
			(net "DRIVE_ACT_9")
			(options
				(clearance outline)
				(anchor circle)
			)
			(primitives
				(gr_poly
					(pts
						(arc
							(start -0.1778 -0.2794)
							(mid -0.249642 -0.249642)
							(end -0.2794 -0.1778)
						)
						(arc
							(start -0.2794 0.1778)
							(mid -0.249642 0.249642)
							(end -0.1778 0.2794)
						)
						(arc
							(start 0.1778 0.2794)
							(mid 0.249642 0.249642)
							(end 0.2794 0.1778)
						)
						(arc
							(start 0.2794 -0.1778)
							(mid 0.249642 -0.249642)
							(end 0.1778 -0.2794)
						)
					)
					(width 0)
					(fill yes)
				)
			)
		)
	)
	(footprint ""
		(layer "F.Cu")
		(at 176.669446 -462.695036 90)
		(property "Reference" "R379"
			(at 0 0 90)
			(layer "F.SilkS")
			(hide yes)
			(effects
				(font
					(size 1.27 1.27)
				)
			)
		)
		(property "Value" "0R2J-2-GP"
			(at 0.064008 -3.993896 90)
			(unlocked yes)
			(layer "F.Fab")
			(hide yes)
			(effects
				(font
					(size 1.016 1.016)
					(thickness 0.1524)
				)
			)
		)
		(property "Device Type" "R402H16"
			(at 0.064008 -5.517896 90)
			(unlocked yes)
			(layer "F.Fab")
			(hide yes)
			(effects
				(font
					(size 1.016 1.016)
					(thickness 0.1524)
				)
			)
		)
		(duplicate_pad_numbers_are_jumpers no)
		(fp_line
			(start 0.508 -0.9398)
			(end -0.508 -0.9398)
			(stroke
				(width 0.1524)
				(type default)
			)
			(layer "F.SilkS")
		)
		(fp_line
			(start -0.508 -0.9398)
			(end -0.508 0.9398)
			(stroke
				(width 0.1524)
				(type default)
			)
			(layer "F.SilkS")
		)
		(fp_rect
			(start -0.508 0.9398)
			(end 0.508 -0.9398)
			(stroke
				(width 0)
				(type default)
			)
			(fill no)
			(layer "F.CrtYd")
		)
		(fp_rect
			(start -0.508 0.9398)
			(end 0.508 -0.9398)
			(stroke
				(width 0)
				(type default)
			)
			(fill no)
			(layer "F.Fab")
		)
		(pad "1" smd custom
			(at 0 -0.4445 90)
			(size 0.1397 0.1397)
			(layers "F.Cu" "F.Mask" "F.Paste")
			(net "VOL_SEN_SCL")
			(options
				(clearance outline)
				(anchor circle)
			)
			(primitives
				(gr_poly
					(pts
						(arc
							(start -0.1778 -0.2794)
							(mid -0.249642 -0.249642)
							(end -0.2794 -0.1778)
						)
						(arc
							(start -0.2794 0.1778)
							(mid -0.249642 0.249642)
							(end -0.1778 0.2794)
						)
						(arc
							(start 0.1778 0.2794)
							(mid 0.249642 0.249642)
							(end 0.2794 0.1778)
						)
						(arc
							(start 0.2794 -0.1778)
							(mid 0.249642 -0.249642)
							(end 0.1778 -0.2794)
						)
					)
					(width 0)
					(fill yes)
				)
			)
		)
		(pad "2" smd custom
			(at 0 0.4445 90)
			(size 0.1397 0.1397)
			(layers "F.Cu" "F.Mask" "F.Paste")
			(net "I2C_B_SCL")
			(options
				(clearance outline)
				(anchor circle)
			)
			(primitives
				(gr_poly
					(pts
						(arc
							(start -0.1778 -0.2794)
							(mid -0.249642 -0.249642)
							(end -0.2794 -0.1778)
						)
						(arc
							(start -0.2794 0.1778)
							(mid -0.249642 0.249642)
							(end -0.1778 0.2794)
						)
						(arc
							(start 0.1778 0.2794)
							(mid 0.249642 0.249642)
							(end 0.2794 0.1778)
						)
						(arc
							(start 0.2794 -0.1778)
							(mid 0.249642 -0.249642)
							(end 0.1778 -0.2794)
						)
					)
					(width 0)
					(fill yes)
				)
			)
		)
	)
)
